(kicad_pcb
	(version 20260206)
	(generator "pcbnew")
	(generator_version "10.0")
	(general
		(thickness 1.6)
		(legacy_teardrops no)
	)
	(paper "A4")
	(title_block
		(title "03242023_DA0F0TMBIJ0_F0T_Motherboard_J_brd_V01_OCP.brd")
		(comment 1 "Grand Teton / footprint 3133 of 6105 (J32), pads 113-224 of 291")
	)
	(layers
		(0 "F.Cu" signal "TOP")
		(4 "In1.Cu" signal "GND")
		(6 "In2.Cu" signal "IN1")
		(8 "In3.Cu" signal "GND1")
		(10 "In4.Cu" signal "IN2")
		(12 "In5.Cu" signal "GND2")
		(14 "In6.Cu" signal "IN3")
		(16 "In7.Cu" signal "GND3")
		(18 "In8.Cu" signal "VCC")
		(20 "In9.Cu" signal "VCC1")
		(22 "In10.Cu" signal "GND4")
		(24 "In11.Cu" signal "IN4")
		(26 "In12.Cu" signal "GND5")
		(28 "In13.Cu" signal "IN5")
		(30 "In14.Cu" signal "GND6")
		(32 "In15.Cu" signal "IN6")
		(34 "In16.Cu" signal "GND7")
		(2 "B.Cu" signal "BOTTOM")
		(9 "F.Adhes" user "F.Adhesive")
		(11 "B.Adhes" user "B.Adhesive")
		(13 "F.Paste" user "Package Geometry/Pastemask Top")
		(15 "B.Paste" user "Package Geometry/Pastemask Bottom")
		(5 "F.SilkS" user "Ref Des/Silkscreen Top")
		(7 "B.SilkS" user "Ref Des/Silkscreen Bottom")
		(1 "F.Mask" user "Board Geometry/Soldermask Top")
		(3 "B.Mask" user "Board Geometry/Soldermask Bottom")
		(17 "Dwgs.User" user "User.Drawings")
		(19 "Cmts.User" user "User.Comments")
		(21 "Eco1.User" user "User.Eco1")
		(23 "Eco2.User" user "User.Eco2")
		(25 "Edge.Cuts" user "Board Geometry/Outline")
		(27 "Margin" user)
		(31 "F.CrtYd" user "Package Geometry/Place Bound Top")
		(29 "B.CrtYd" user "Package Geometry/Place Bound Bottom")
		(35 "F.Fab" user "Ref Des/Assembly Top")
		(33 "B.Fab" user "Ref Des/Assembly Bottom")
	)
	(footprint ""
		(layer "F.Cu")
		(at 206.12608 -258.091686)
		(property "Reference" "J32"
			(at 0.68834 -81.826608 0)
			(unlocked yes)
			(layer "F.SilkS")
			(effects
				(font
					(size 0.7874 0.5842)
					(thickness 0.1524)
				)
				(justify left)
			)
		)
		(property "Value" ""
			(at 0 0 0)
			(layer "F.Fab")
			(effects
				(font
					(size 1.27 1.27)
				)
			)
		)
		(duplicate_pad_numbers_are_jumpers no)
		(pad "113" smd rect
			(at -2.050034 36.975034 270)
			(size 0.519938 1.4986)
			(layers "F.Cu" "F.Mask" "F.Paste")
			(net "M_H_CPU1_SB_DQ<9>")
		)
		(pad "114" smd rect
			(at -2.050034 37.824918 270)
			(size 0.519938 1.4986)
			(layers "F.Cu" "F.Mask" "F.Paste")
			(net "GND")
		)
		(pad "115" smd rect
			(at -2.050034 38.675056 270)
			(size 0.519938 1.4986)
			(layers "F.Cu" "F.Mask" "F.Paste")
			(net "M_H_CPU1_SB_DQS_DP<1>")
		)
		(pad "116" smd rect
			(at -2.050034 39.52494 270)
			(size 0.519938 1.4986)
			(layers "F.Cu" "F.Mask" "F.Paste")
			(net "M_H_CPU1_SB_DQS_DN<1>")
		)
		(pad "117" smd rect
			(at -2.050034 40.375078 270)
			(size 0.519938 1.4986)
			(layers "F.Cu" "F.Mask" "F.Paste")
			(net "GND")
		)
		(pad "118" smd rect
			(at -2.050034 41.224962 270)
			(size 0.519938 1.4986)
			(layers "F.Cu" "F.Mask" "F.Paste")
			(net "M_H_CPU1_SB_DQ<12>")
		)
		(pad "119" smd rect
			(at -2.050034 42.0751 270)
			(size 0.519938 1.4986)
			(layers "F.Cu" "F.Mask" "F.Paste")
			(net "GND")
		)
		(pad "120" smd rect
			(at -2.050034 42.924984 270)
			(size 0.519938 1.4986)
			(layers "F.Cu" "F.Mask" "F.Paste")
			(net "M_H_CPU1_SB_DQ<13>")
		)
		(pad "121" smd rect
			(at -2.050034 43.775122 270)
			(size 0.519938 1.4986)
			(layers "F.Cu" "F.Mask" "F.Paste")
			(net "GND")
		)
		(pad "122" smd rect
			(at -2.050034 44.625006 270)
			(size 0.519938 1.4986)
			(layers "F.Cu" "F.Mask" "F.Paste")
			(net "M_H_CPU1_SB_DQ<16>")
		)
		(pad "123" smd rect
			(at -2.050034 45.47489 270)
			(size 0.519938 1.4986)
			(layers "F.Cu" "F.Mask" "F.Paste")
			(net "GND")
		)
		(pad "124" smd rect
			(at -2.050034 46.325028 270)
			(size 0.519938 1.4986)
			(layers "F.Cu" "F.Mask" "F.Paste")
			(net "M_H_CPU1_SB_DQ<17>")
		)
		(pad "125" smd rect
			(at -2.050034 47.174912 270)
			(size 0.519938 1.4986)
			(layers "F.Cu" "F.Mask" "F.Paste")
			(net "GND")
		)
		(pad "126" smd rect
			(at -2.050034 48.02505 270)
			(size 0.519938 1.4986)
			(layers "F.Cu" "F.Mask" "F.Paste")
			(net "M_H_CPU1_SB_DQS_DP<2>")
		)
		(pad "127" smd rect
			(at -2.050034 48.874934 270)
			(size 0.519938 1.4986)
			(layers "F.Cu" "F.Mask" "F.Paste")
			(net "M_H_CPU1_SB_DQS_DN<2>")
		)
		(pad "128" smd rect
			(at -2.050034 49.725072 270)
			(size 0.519938 1.4986)
			(layers "F.Cu" "F.Mask" "F.Paste")
			(net "GND")
		)
		(pad "129" smd rect
			(at -2.050034 50.574956 270)
			(size 0.519938 1.4986)
			(layers "F.Cu" "F.Mask" "F.Paste")
			(net "M_H_CPU1_SB_DQ<20>")
		)
		(pad "130" smd rect
			(at -2.050034 51.425094 270)
			(size 0.519938 1.4986)
			(layers "F.Cu" "F.Mask" "F.Paste")
			(net "GND")
		)
		(pad "131" smd rect
			(at -2.050034 52.274978 270)
			(size 0.519938 1.4986)
			(layers "F.Cu" "F.Mask" "F.Paste")
			(net "M_H_CPU1_SB_DQ<21>")
		)
		(pad "132" smd rect
			(at -2.050034 53.125116 270)
			(size 0.519938 1.4986)
			(layers "F.Cu" "F.Mask" "F.Paste")
			(net "GND")
		)
		(pad "133" smd rect
			(at -2.050034 53.975 270)
			(size 0.519938 1.4986)
			(layers "F.Cu" "F.Mask" "F.Paste")
			(net "M_H_CPU1_SB_DQ<24>")
		)
		(pad "134" smd rect
			(at -2.050034 54.824884 270)
			(size 0.519938 1.4986)
			(layers "F.Cu" "F.Mask" "F.Paste")
			(net "GND")
		)
		(pad "135" smd rect
			(at -2.050034 55.675022 270)
			(size 0.519938 1.4986)
			(layers "F.Cu" "F.Mask" "F.Paste")
			(net "M_H_CPU1_SB_DQ<25>")
		)
		(pad "136" smd rect
			(at -2.050034 56.524906 270)
			(size 0.519938 1.4986)
			(layers "F.Cu" "F.Mask" "F.Paste")
			(net "GND")
		)
		(pad "137" smd rect
			(at -2.050034 57.375044 270)
			(size 0.519938 1.4986)
			(layers "F.Cu" "F.Mask" "F.Paste")
			(net "M_H_CPU1_SB_DQS_DP<3>")
		)
		(pad "138" smd rect
			(at -2.050034 58.224928 270)
			(size 0.519938 1.4986)
			(layers "F.Cu" "F.Mask" "F.Paste")
			(net "M_H_CPU1_SB_DQS_DN<3>")
		)
		(pad "139" smd rect
			(at -2.050034 59.075066 270)
			(size 0.519938 1.4986)
			(layers "F.Cu" "F.Mask" "F.Paste")
			(net "GND")
		)
		(pad "140" smd rect
			(at -2.050034 59.92495 270)
			(size 0.519938 1.4986)
			(layers "F.Cu" "F.Mask" "F.Paste")
			(net "M_H_CPU1_SB_DQ<28>")
		)
		(pad "141" smd rect
			(at -2.050034 60.775088 270)
			(size 0.519938 1.4986)
			(layers "F.Cu" "F.Mask" "F.Paste")
			(net "GND")
		)
		(pad "142" smd rect
			(at -2.050034 61.624972 270)
			(size 0.519938 1.4986)
			(layers "F.Cu" "F.Mask" "F.Paste")
			(net "M_H_CPU1_SB_DQ<29>")
		)
		(pad "143" smd rect
			(at -2.050034 62.47511 270)
			(size 0.519938 1.4986)
			(layers "F.Cu" "F.Mask" "F.Paste")
			(net "GND")
		)
		(pad "144" smd rect
			(at -2.050034 63.324994 270)
			(size 0.519938 1.4986)
			(layers "F.Cu" "F.Mask" "F.Paste")
			(net "TP_CHH_CPU1_DIMM2_FRU_1")
		)
		(pad "145" smd rect
			(at 2.050034 -63.324994 270)
			(size 0.519938 1.4986)
			(layers "F.Cu" "F.Mask" "F.Paste")
			(net "P12V_S3_AUX_CPU1_NVDIMM")
		)
		(pad "146" smd rect
			(at 2.050034 -62.47511 270)
			(size 0.519938 1.4986)
			(layers "F.Cu" "F.Mask" "F.Paste")
			(net "P12V_S3_AUX_CPU1_NVDIMM")
		)
		(pad "147" smd rect
			(at 2.050034 -61.624972 270)
			(size 0.519938 1.4986)
			(layers "F.Cu" "F.Mask" "F.Paste")
			(net "PWRGD_CHH_CPU1_DIMM2")
		)
		(pad "148" smd rect
			(at 2.050034 -60.775088 270)
			(size 0.519938 1.4986)
			(layers "F.Cu" "F.Mask" "F.Paste")
			(net "PD_CHH_CPU1_DIMM2_SAA")
		)
		(pad "149" smd rect
			(at 2.050034 -59.92495 270)
			(size 0.519938 1.4986)
			(layers "F.Cu" "F.Mask" "F.Paste")
			(net "TP_CHH_CPU1_DIMM2_FRU_2")
		)
		(pad "150" smd rect
			(at 2.050034 -59.075066 270)
			(size 0.519938 1.4986)
			(layers "F.Cu" "F.Mask" "F.Paste")
			(net "TP_CHH_CPU1_DIMM2_FRU_3")
		)
		(pad "151" smd rect
			(at 2.050034 -58.224928 270)
			(size 0.519938 1.4986)
			(layers "F.Cu" "F.Mask" "F.Paste")
			(net "GND")
		)
		(pad "152" smd rect
			(at 2.050034 -57.375044 270)
			(size 0.519938 1.4986)
			(layers "F.Cu" "F.Mask" "F.Paste")
			(net "M_H_CPU1_SA_DQ<2>")
		)
		(pad "153" smd rect
			(at 2.050034 -56.524906 270)
			(size 0.519938 1.4986)
			(layers "F.Cu" "F.Mask" "F.Paste")
			(net "GND")
		)
		(pad "154" smd rect
			(at 2.050034 -55.675022 270)
			(size 0.519938 1.4986)
			(layers "F.Cu" "F.Mask" "F.Paste")
			(net "M_H_CPU1_SA_DQ<3>")
		)
		(pad "155" smd rect
			(at 2.050034 -54.824884 270)
			(size 0.519938 1.4986)
			(layers "F.Cu" "F.Mask" "F.Paste")
			(net "GND")
		)
		(pad "156" smd rect
			(at 2.050034 -53.975 270)
			(size 0.519938 1.4986)
			(layers "F.Cu" "F.Mask" "F.Paste")
			(net "M_H_CPU1_SA_DQS_DN<5>")
		)
		(pad "157" smd rect
			(at 2.050034 -53.125116 270)
			(size 0.519938 1.4986)
			(layers "F.Cu" "F.Mask" "F.Paste")
			(net "M_H_CPU1_SA_DQS_DP<5>")
		)
		(pad "158" smd rect
			(at 2.050034 -52.274978 270)
			(size 0.519938 1.4986)
			(layers "F.Cu" "F.Mask" "F.Paste")
			(net "GND")
		)
		(pad "159" smd rect
			(at 2.050034 -51.425094 270)
			(size 0.519938 1.4986)
			(layers "F.Cu" "F.Mask" "F.Paste")
			(net "M_H_CPU1_SA_DQ<6>")
		)
		(pad "160" smd rect
			(at 2.050034 -50.574956 270)
			(size 0.519938 1.4986)
			(layers "F.Cu" "F.Mask" "F.Paste")
			(net "GND")
		)
		(pad "161" smd rect
			(at 2.050034 -49.725072 270)
			(size 0.519938 1.4986)
			(layers "F.Cu" "F.Mask" "F.Paste")
			(net "M_H_CPU1_SA_DQ<7>")
		)
		(pad "162" smd rect
			(at 2.050034 -48.874934 270)
			(size 0.519938 1.4986)
			(layers "F.Cu" "F.Mask" "F.Paste")
			(net "GND")
		)
		(pad "163" smd rect
			(at 2.050034 -48.02505 270)
			(size 0.519938 1.4986)
			(layers "F.Cu" "F.Mask" "F.Paste")
			(net "M_H_CPU1_SA_DQ<10>")
		)
		(pad "164" smd rect
			(at 2.050034 -47.174912 270)
			(size 0.519938 1.4986)
			(layers "F.Cu" "F.Mask" "F.Paste")
			(net "GND")
		)
		(pad "165" smd rect
			(at 2.050034 -46.325028 270)
			(size 0.519938 1.4986)
			(layers "F.Cu" "F.Mask" "F.Paste")
			(net "M_H_CPU1_SA_DQ<11>")
		)
		(pad "166" smd rect
			(at 2.050034 -45.47489 270)
			(size 0.519938 1.4986)
			(layers "F.Cu" "F.Mask" "F.Paste")
			(net "GND")
		)
		(pad "167" smd rect
			(at 2.050034 -44.625006 270)
			(size 0.519938 1.4986)
			(layers "F.Cu" "F.Mask" "F.Paste")
			(net "M_H_CPU1_SA_DQS_DN<6>")
		)
		(pad "168" smd rect
			(at 2.050034 -43.775122 270)
			(size 0.519938 1.4986)
			(layers "F.Cu" "F.Mask" "F.Paste")
			(net "M_H_CPU1_SA_DQS_DP<6>")
		)
		(pad "169" smd rect
			(at 2.050034 -42.924984 270)
			(size 0.519938 1.4986)
			(layers "F.Cu" "F.Mask" "F.Paste")
			(net "GND")
		)
		(pad "170" smd rect
			(at 2.050034 -42.0751 270)
			(size 0.519938 1.4986)
			(layers "F.Cu" "F.Mask" "F.Paste")
			(net "M_H_CPU1_SA_DQ<14>")
		)
		(pad "171" smd rect
			(at 2.050034 -41.224962 270)
			(size 0.519938 1.4986)
			(layers "F.Cu" "F.Mask" "F.Paste")
			(net "GND")
		)
		(pad "172" smd rect
			(at 2.050034 -40.375078 270)
			(size 0.519938 1.4986)
			(layers "F.Cu" "F.Mask" "F.Paste")
			(net "M_H_CPU1_SA_DQ<15>")
		)
		(pad "173" smd rect
			(at 2.050034 -39.52494 270)
			(size 0.519938 1.4986)
			(layers "F.Cu" "F.Mask" "F.Paste")
			(net "GND")
		)
		(pad "174" smd rect
			(at 2.050034 -38.675056 270)
			(size 0.519938 1.4986)
			(layers "F.Cu" "F.Mask" "F.Paste")
			(net "M_H_CPU1_SA_DQ<18>")
		)
		(pad "175" smd rect
			(at 2.050034 -37.824918 270)
			(size 0.519938 1.4986)
			(layers "F.Cu" "F.Mask" "F.Paste")
			(net "GND")
		)
		(pad "176" smd rect
			(at 2.050034 -36.975034 270)
			(size 0.519938 1.4986)
			(layers "F.Cu" "F.Mask" "F.Paste")
			(net "M_H_CPU1_SA_DQ<19>")
		)
		(pad "177" smd rect
			(at 2.050034 -36.124896 270)
			(size 0.519938 1.4986)
			(layers "F.Cu" "F.Mask" "F.Paste")
			(net "GND")
		)
		(pad "178" smd rect
			(at 2.050034 -35.275012 270)
			(size 0.519938 1.4986)
			(layers "F.Cu" "F.Mask" "F.Paste")
			(net "M_H_CPU1_SA_DQS_DN<7>")
		)
		(pad "179" smd rect
			(at 2.050034 -34.425128 270)
			(size 0.519938 1.4986)
			(layers "F.Cu" "F.Mask" "F.Paste")
			(net "M_H_CPU1_SA_DQS_DP<7>")
		)
		(pad "180" smd rect
			(at 2.050034 -33.57499 270)
			(size 0.519938 1.4986)
			(layers "F.Cu" "F.Mask" "F.Paste")
			(net "GND")
		)
		(pad "181" smd rect
			(at 2.050034 -32.725106 270)
			(size 0.519938 1.4986)
			(layers "F.Cu" "F.Mask" "F.Paste")
			(net "M_H_CPU1_SA_DQ<22>")
		)
		(pad "182" smd rect
			(at 2.050034 -31.874968 270)
			(size 0.519938 1.4986)
			(layers "F.Cu" "F.Mask" "F.Paste")
			(net "GND")
		)
		(pad "183" smd rect
			(at 2.050034 -31.025084 270)
			(size 0.519938 1.4986)
			(layers "F.Cu" "F.Mask" "F.Paste")
			(net "M_H_CPU1_SA_DQ<23>")
		)
		(pad "184" smd rect
			(at 2.050034 -30.174946 270)
			(size 0.519938 1.4986)
			(layers "F.Cu" "F.Mask" "F.Paste")
			(net "GND")
		)
		(pad "185" smd rect
			(at 2.050034 -29.325062 270)
			(size 0.519938 1.4986)
			(layers "F.Cu" "F.Mask" "F.Paste")
			(net "M_H_CPU1_SA_DQ<26>")
		)
		(pad "186" smd rect
			(at 2.050034 -28.474924 270)
			(size 0.519938 1.4986)
			(layers "F.Cu" "F.Mask" "F.Paste")
			(net "GND")
		)
		(pad "187" smd rect
			(at 2.050034 -27.62504 270)
			(size 0.519938 1.4986)
			(layers "F.Cu" "F.Mask" "F.Paste")
			(net "M_H_CPU1_SA_DQ<27>")
		)
		(pad "188" smd rect
			(at 2.050034 -26.774902 270)
			(size 0.519938 1.4986)
			(layers "F.Cu" "F.Mask" "F.Paste")
			(net "GND")
		)
		(pad "189" smd rect
			(at 2.050034 -25.925018 270)
			(size 0.519938 1.4986)
			(layers "F.Cu" "F.Mask" "F.Paste")
			(net "M_H_CPU1_SA_DQS_DN<8>")
		)
		(pad "190" smd rect
			(at 2.050034 -25.07488 270)
			(size 0.519938 1.4986)
			(layers "F.Cu" "F.Mask" "F.Paste")
			(net "M_H_CPU1_SA_DQS_DP<8>")
		)
		(pad "191" smd rect
			(at 2.050034 -24.224996 270)
			(size 0.519938 1.4986)
			(layers "F.Cu" "F.Mask" "F.Paste")
			(net "GND")
		)
		(pad "192" smd rect
			(at 2.050034 -23.375112 270)
			(size 0.519938 1.4986)
			(layers "F.Cu" "F.Mask" "F.Paste")
			(net "M_H_CPU1_SA_DQ<30>")
		)
		(pad "193" smd rect
			(at 2.050034 -22.524974 270)
			(size 0.519938 1.4986)
			(layers "F.Cu" "F.Mask" "F.Paste")
			(net "GND")
		)
		(pad "194" smd rect
			(at 2.050034 -21.67509 270)
			(size 0.519938 1.4986)
			(layers "F.Cu" "F.Mask" "F.Paste")
			(net "M_H_CPU1_SA_DQ<31>")
		)
		(pad "195" smd rect
			(at 2.050034 -20.824952 270)
			(size 0.519938 1.4986)
			(layers "F.Cu" "F.Mask" "F.Paste")
			(net "GND")
		)
		(pad "196" smd rect
			(at 2.050034 -19.975068 270)
			(size 0.519938 1.4986)
			(layers "F.Cu" "F.Mask" "F.Paste")
			(net "M_H_CPU1_SA_CB<2>")
		)
		(pad "197" smd rect
			(at 2.050034 -19.12493 270)
			(size 0.519938 1.4986)
			(layers "F.Cu" "F.Mask" "F.Paste")
			(net "GND")
		)
		(pad "198" smd rect
			(at 2.050034 -18.275046 270)
			(size 0.519938 1.4986)
			(layers "F.Cu" "F.Mask" "F.Paste")
			(net "M_H_CPU1_SA_CB<3>")
		)
		(pad "199" smd rect
			(at 2.050034 -17.424908 270)
			(size 0.519938 1.4986)
			(layers "F.Cu" "F.Mask" "F.Paste")
			(net "GND")
		)
		(pad "200" smd rect
			(at 2.050034 -16.575024 270)
			(size 0.519938 1.4986)
			(layers "F.Cu" "F.Mask" "F.Paste")
			(net "M_H_CPU1_SA_DQS_DN<9>")
		)
		(pad "201" smd rect
			(at 2.050034 -15.724886 270)
			(size 0.519938 1.4986)
			(layers "F.Cu" "F.Mask" "F.Paste")
			(net "M_H_CPU1_SA_DQS_DP<9>")
		)
		(pad "202" smd rect
			(at 2.050034 -14.875002 270)
			(size 0.519938 1.4986)
			(layers "F.Cu" "F.Mask" "F.Paste")
			(net "GND")
		)
		(pad "203" smd rect
			(at 2.050034 -14.025118 270)
			(size 0.519938 1.4986)
			(layers "F.Cu" "F.Mask" "F.Paste")
			(net "M_H_CPU1_SA_CB<6>")
		)
		(pad "204" smd rect
			(at 2.050034 -13.17498 270)
			(size 0.519938 1.4986)
			(layers "F.Cu" "F.Mask" "F.Paste")
			(net "GND")
		)
		(pad "205" smd rect
			(at 2.050034 -12.325096 270)
			(size 0.519938 1.4986)
			(layers "F.Cu" "F.Mask" "F.Paste")
			(net "M_H_CPU1_SA_CB<7>")
		)
		(pad "206" smd rect
			(at 2.050034 -11.474958 270)
			(size 0.519938 1.4986)
			(layers "F.Cu" "F.Mask" "F.Paste")
			(net "GND")
		)
		(pad "207" smd rect
			(at 2.050034 -10.625074 270)
			(size 0.519938 1.4986)
			(layers "F.Cu" "F.Mask" "F.Paste")
			(net "RST_M_GH_CPU1_FPGA_N")
		)
		(pad "208" smd rect
			(at 2.050034 -9.774936 270)
			(size 0.519938 1.4986)
			(layers "F.Cu" "F.Mask" "F.Paste")
			(net "GND")
		)
		(pad "209" smd rect
			(at 2.050034 -8.925052 270)
			(size 0.519938 1.4986)
			(layers "F.Cu" "F.Mask" "F.Paste")
			(net "M_H_CPU1_SA_CS_N<3>")
		)
		(pad "210" smd rect
			(at 2.050034 -8.074914 270)
			(size 0.519938 1.4986)
			(layers "F.Cu" "F.Mask" "F.Paste")
			(net "GND")
		)
		(pad "211" smd rect
			(at 2.050034 -7.22503 270)
			(size 0.519938 1.4986)
			(layers "F.Cu" "F.Mask" "F.Paste")
			(net "M_H_CPU1_SA_CA<1>")
		)
		(pad "212" smd rect
			(at 2.050034 -6.374892 270)
			(size 0.519938 1.4986)
			(layers "F.Cu" "F.Mask" "F.Paste")
			(net "GND")
		)
		(pad "213" smd rect
			(at 2.050034 -5.525008 270)
			(size 0.519938 1.4986)
			(layers "F.Cu" "F.Mask" "F.Paste")
			(net "M_H_CPU1_SA_CA<3>")
		)
		(pad "214" smd rect
			(at 2.050034 -4.675124 270)
			(size 0.519938 1.4986)
			(layers "F.Cu" "F.Mask" "F.Paste")
			(net "GND")
		)
		(pad "215" smd rect
			(at 2.050034 -3.824986 270)
			(size 0.519938 1.4986)
			(layers "F.Cu" "F.Mask" "F.Paste")
			(net "M_H_CPU1_SA_CA<5>")
		)
		(pad "216" smd rect
			(at 2.050034 -2.975102 270)
			(size 0.519938 1.4986)
			(layers "F.Cu" "F.Mask" "F.Paste")
			(net "GND")
		)
		(pad "217" smd rect
			(at 2.050034 -2.124964 270)
			(size 0.519938 1.4986)
			(layers "F.Cu" "F.Mask" "F.Paste")
			(net "M_H_CPU1_CLK_DP<1>")
		)
		(pad "218" smd rect
			(at 2.050034 -1.27508 270)
			(size 0.519938 1.4986)
			(layers "F.Cu" "F.Mask" "F.Paste")
			(net "M_H_CPU1_CLK_DN<1>")
		)
		(pad "219" smd rect
			(at 2.050034 -0.424942 270)
			(size 0.519938 1.4986)
			(layers "F.Cu" "F.Mask" "F.Paste")
			(net "GND")
		)
		(pad "220" smd rect
			(at 2.050034 5.525008 270)
			(size 0.519938 1.4986)
			(layers "F.Cu" "F.Mask" "F.Paste")
			(net "TP_CHH_CPU1_DIMM2_FRU_4")
		)
		(pad "221" smd rect
			(at 2.050034 6.374892 270)
			(size 0.519938 1.4986)
			(layers "F.Cu" "F.Mask" "F.Paste")
			(net "M_H_CPU1_SB_CA<1>")
		)
		(pad "222" smd rect
			(at 2.050034 7.22503 270)
			(size 0.519938 1.4986)
			(layers "F.Cu" "F.Mask" "F.Paste")
			(net "GND")
		)
		(pad "223" smd rect
			(at 2.050034 8.074914 270)
			(size 0.519938 1.4986)
			(layers "F.Cu" "F.Mask" "F.Paste")
			(net "M_H_CPU1_SB_CA<3>")
		)
		(pad "224" smd rect
			(at 2.050034 8.925052 270)
			(size 0.519938 1.4986)
			(layers "F.Cu" "F.Mask" "F.Paste")
			(net "GND")
		)
	)
)
